# T6G (Grand Teton) — schematic parts with pin connectivity, parts 5342–5487 of 8303; source: Cadence DE-HDL packaged netlist (pstxprt.dat, pstxnet.dat, pstchip.dat)

R618  Q_RES  0 5% CHIP  pkg 0402LF  page 54 : 1 = CPU1_XTRIG_R2_L5 ; 2 = CPU1_XTRIG_L5
R619  Q_RES  0 5% CHIP  pkg 0201LF  page 342 : 1 = CLK_100M_RETIMER_CPU1_P2_R_DP ; 2 = CLK_100M_RETIMER_CPU1_P2_DP
R620  Q_RES  0 5% CHIP  pkg 0201LF  page 342 : 1 = CLK_100M_RETIMER_CPU1_P2_R_DN ; 2 = CLK_100M_RETIMER_CPU1_P2_DN
R621  Q_RES  0 5% CHIP  pkg 0201LF  page 353 : 1 = CLK_100M_RETIMER_CPU1_P3_R_DP ; 2 = CLK_100M_RETIMER_CPU1_P3_DP
R622  Q_RES  0 5% CHIP  pkg 0201LF  page 353 : 1 = CLK_100M_RETIMER_CPU1_P3_R_DN ; 2 = CLK_100M_RETIMER_CPU1_P3_DN
R623  Q_RES  51.1 1% EMPTY  pkg 0201LF  page 276 : 1 = CLK_100M_RETIMER_CPU0_P0_DN ; 2 = GND
R624  Q_RES  51.1 1% EMPTY  pkg 0201LF  page 276 : 1 = CLK_100M_RETIMER_CPU0_P0_DP ; 2 = GND
R625  Q_RES  51.1 1% EMPTY  pkg 0201LF  page 331 : 1 = CLK_100M_RETIMER_CPU1_P1_DN ; 2 = GND
R626  Q_RES  51.1 1% EMPTY  pkg 0201LF  page 331 : 1 = CLK_100M_RETIMER_CPU1_P1_DP ; 2 = GND
R627  Q_RES  51.1 1% EMPTY  pkg 0201LF  page 320 : 1 = CLK_100M_RETIMER_CPU1_P0_DN ; 2 = GND
R628  Q_RES  51.1 1% EMPTY  pkg 0201LF  page 320 : 1 = CLK_100M_RETIMER_CPU1_P0_DP ; 2 = GND
R629  Q_RES  51.1 1% EMPTY  pkg 0201LF  page 287 : 1 = CLK_100M_RETIMER_CPU0_P1_DN ; 2 = GND
R630  Q_RES  51.1 1% EMPTY  pkg 0201LF  page 287 : 1 = CLK_100M_RETIMER_CPU0_P1_DP ; 2 = GND
R631  Q_RES  51.1 1% EMPTY  pkg 0201LF  page 298 : 1 = CLK_100M_RETIMER_CPU0_P2_DN ; 2 = GND
R632  Q_RES  2.2K 5% CHIP  pkg 0402LF  page 151 : 1 = PVDD18_S5_P0 ; 2 = SMB_CPU_5_SCL
R633  Q_RES  2.2K 5% CHIP  pkg 0402LF  page 151 : 1 = PVDD18_S5_P0 ; 2 = SMB_CPU_5_SDA
R634  Q_RES  51.1 1% EMPTY  pkg 0201LF  page 298 : 1 = CLK_100M_RETIMER_CPU0_P2_DP ; 2 = GND
R635  Q_RES  51.1 1% EMPTY  pkg 0201LF  page 309 : 1 = CLK_100M_RETIMER_CPU0_P3_DN ; 2 = GND
R636  Q_RES  51.1 1% EMPTY  pkg 0201LF  page 309 : 1 = CLK_100M_RETIMER_CPU0_P3_DP ; 2 = GND
R637  Q_RES  51.1 1% EMPTY  pkg 0201LF  page 342 : 1 = CLK_100M_RETIMER_CPU1_P2_DN ; 2 = GND
R638  Q_RES  1K 1% CHIP  pkg 0402LF  page 83 : 1 = CPLD_JTAG_EN ; 2 = P3V3_AUX
R639  Q_RES  1K 1% CHIP  pkg 0402LF  page 83 : 1 = CPLD_PROGRAMN ; 2 = P3V3_AUX
R640  Q_RES  51.1 1% EMPTY  pkg 0201LF  page 342 : 1 = CLK_100M_RETIMER_CPU1_P2_DP ; 2 = GND
R641  Q_RES  51.1 1% EMPTY  pkg 0201LF  page 353 : 1 = CLK_100M_RETIMER_CPU1_P3_DN ; 2 = GND
R642  Q_RES  51.1 1% EMPTY  pkg 0201LF  page 353 : 1 = CLK_100M_RETIMER_CPU1_P3_DP ; 2 = GND
R643  Q_RES  1K 1% EMPTY  pkg 0402LF  page 362 : 1 = P3V3_AUX ; 2 = PWRGD_P0V9_RETIMER_CPU0_R
R644  Q_RES  10K 5% CHIP  pkg 0402LF  page 361 : 1 = P3V3_AUX ; 2 = PWRGD_P1V8_RETIMER_CPU1
R645  Q_RES  33 5% CHIP  pkg 0402LF  page 361 : 1 = PWRGD_P1V8_RETIMER_CPU1 ; 2 = FM_PWRGD_P1V8_RETIMER_CPU1
R646  Q_RES  0 5% CHIP  pkg 0402LF  page 362 : 1 = P0V9_RETIMER_CPU0_PMSCL ; 2 = P0V9_RETIMER_CPU0_PMSCL_R
R647  Q_RES  0 5% CHIP  pkg 0402LF  page 362 : 1 = P0V9_RETIMER_CPU0_PMSDA ; 2 = P0V9_RETIMER_CPU0_PMSDA_R
R648  Q_RES  33 5% CHIP  pkg 0402LF  page 81 : 1 = E1S_0_P3V3_EN ; 2 = P3V3_E1S_0_EN_R
R649  Q_RES  4.7K 1% EMPTY  pkg 0402LF  page 362 : 1 = P3V3_AUX ; 2 = TP_P0V9_RETIMER_CPU0_PMALERT
R650  Q_RES  0 5% CHIP  pkg 0402LF  page 362 : 1 = PWRGD_P0V9_RETIMER_CPU0 ; 2 = PWRGD_P0V9_RETIMER_CPU0_R
R651  Q_RES  0 5% CHIP  pkg 0402LF  page 362 : 1 = P0V9_RETIMER_CPU0_EN ; 2 = P0V9_RETIMER_CPU0_EN0_R
R652  Q_RES  1K 1% CHIP  pkg 0402LF  page 362 : 1 = P3V3_AUX ; 2 = P0V9_RETIMER_CPU0_CFP
R653  Q_RES  0 5% EMPTY  pkg 0402LF  page 334 : 1 = P1V8_CPU1_RT1_1A_1D ; 2 = P1V8_CPU1_RT1_1A
R654  Q_RES  4.7K 5% CHIP  pkg 0402LF  page 83 : 1 = SCM_USB_OC_N ; 2 = P1V8_AUX
R655  Q_RES  1K 1% CHIP  pkg 0402LF  page 362 : 1 = P3V3_AUX ; 2 = P0V9_RETIMER_CPU0_INALERT
R656  Q_RES  1K 1% EMPTY  pkg 0402LF  page 364 : 1 = P3V3_AUX ; 2 = PWRGD_P0V9_RETIMER_CPU1_R
R657  Q_RES  0 5% CHIP  pkg 0402LF  page 364 : 1 = P0V9_RETIMER_CPU1_PMSCL ; 2 = P0V9_RETIMER_CPU1_PMSCL_R
R658  Q_RES  0 5% CHIP  pkg 0402LF  page 364 : 1 = P0V9_RETIMER_CPU1_PMSDA ; 2 = P0V9_RETIMER_CPU1_PMSDA_R
R659  Q_RES  1K 1% CHIP  pkg 0402LF  page 77 : 1 = PVDD18_S5_P0 ; 2 = SPI_CPU0_TPM_CS_N
R660  Q_RES  4.7K 1% EMPTY  pkg 0402LF  page 364 : 1 = P3V3_AUX ; 2 = TP_P0V9_RETIMER_CPU1_PMALERT
R661  Q_RES  0 5% CHIP  pkg 0402LF  page 364 : 1 = PWRGD_P0V9_RETIMER_CPU1 ; 2 = PWRGD_P0V9_RETIMER_CPU1_R
R662  Q_RES  0 5% CHIP  pkg 0402LF  page 364 : 1 = P0V9_RETIMER_CPU1_EN ; 2 = P0V9_RETIMER_CPU1_EN0_R
R663  Q_RES  1K 1% CHIP  pkg 0402LF  page 364 : 1 = P3V3_AUX ; 2 = P0V9_RETIMER_CPU1_CFP
R664  Q_RES  0 5% EMPTY  pkg 0402LF  page 334 : 1 = P1V8_CPU1_RT1_1A_1D ; 2 = P1V8_CPU1_RT1_1A
R665  Q_RES  1K 1% CHIP  pkg 0402LF  page 364 : 1 = P3V3_AUX ; 2 = P0V9_RETIMER_CPU1_INALERT
R666  Q_RES  49.9 1% CHIP  pkg 0201LF  page 276 : 1 = SMB_RT_CPU0_P0_ROM_MUX_1D_SCL ; 2 = SMB_RT_CPU0_P0_ROM_MUX_1D_R_SCL
R667  Q_RES  49.9 1% CHIP  pkg 0201LF  page 276 : 1 = SMB_RT_CPU0_P0_ROM_MUX_1D_SDA ; 2 = SMB_RT_CPU0_P0_ROM_MUX_1D_R_SDA
R668  Q_RES  33.2 1% CHIP  pkg 0201LF  page 278 : 1 = SMB_RT_CPU0_P0_ROM_R_SCL ; 2 = SMB_RT_CPU0_P0_ROM_SCL
R669  Q_RES  33.2 1% CHIP  pkg 0201LF  page 278 : 1 = SMB_RT_CPU0_P0_ROM_R_SDA ; 2 = SMB_RT_CPU0_P0_ROM_SDA
R670  Q_RES  49.9 1% CHIP  pkg 0201LF  page 331 : 1 = SMB_RT_CPU1_P1_ROM_MUX_1D_SCL ; 2 = SMB_RT_CPU1_P1_ROM_MUX_1D_R_SCL
R671  Q_RES  49.9 1% CHIP  pkg 0201LF  page 331 : 1 = SMB_RT_CPU1_P1_ROM_MUX_1D_SDA ; 2 = SMB_RT_CPU1_P1_ROM_MUX_1D_R_SDA
R672  Q_RES  33.2 1% CHIP  pkg 0201LF  page 322 : 1 = SMB_RT_CPU1_P0_ROM_R_SCL ; 2 = SMB_RT_CPU1_P0_ROM_SCL
R673  Q_RES  33.2 1% CHIP  pkg 0201LF  page 322 : 1 = SMB_RT_CPU1_P0_ROM_R_SDA ; 2 = SMB_RT_CPU1_P0_ROM_SDA
R674  Q_RES  22 1% CHIP  pkg 0201LF  page 320 : 1 = SMB_RT_CPU1_P0_ROM_MUX_1D_SCL ; 2 = SMB_RT_CPU1_P0_ROM_MUX_1D_R_SCL
R675  Q_RES  49.9 1% CHIP  pkg 0201LF  page 320 : 1 = SMB_RT_CPU1_P0_ROM_MUX_1D_SDA ; 2 = SMB_RT_CPU1_P0_ROM_MUX_1D_R_SDA
R676  Q_RES  49.9 1% CHIP  pkg 0201LF  page 287 : 1 = SMB_RT_CPU0_P1_ROM_MUX_1D_SCL ; 2 = SMB_RT_CPU0_P1_ROM_MUX_1D_R_SCL
R677  Q_RES  49.9 1% CHIP  pkg 0201LF  page 287 : 1 = SMB_RT_CPU0_P1_ROM_MUX_1D_SDA ; 2 = SMB_RT_CPU0_P1_ROM_MUX_1D_R_SDA
R678  Q_RES  33.2 1% CHIP  pkg 0201LF  page 289 : 1 = SMB_RT_CPU0_P1_ROM_R_SCL ; 2 = SMB_RT_CPU0_P1_ROM_SCL
R679  Q_RES  33.2 1% CHIP  pkg 0201LF  page 289 : 1 = SMB_RT_CPU0_P1_ROM_R_SDA ; 2 = SMB_RT_CPU0_P1_ROM_SDA
R680  Q_RES  49.9 1% CHIP  pkg 0201LF  page 298 : 1 = SMB_RT_CPU0_P2_ROM_MUX_1D_SCL ; 2 = SMB_RT_CPU0_P2_ROM_MUX_1D_R_SCL
R681  Q_RES  49.9 1% CHIP  pkg 0201LF  page 298 : 1 = SMB_RT_CPU0_P2_ROM_MUX_1D_SDA ; 2 = SMB_RT_CPU0_P2_ROM_MUX_1D_R_SDA
R682  Q_RES  33.2 1% CHIP  pkg 0201LF  page 300 : 1 = SMB_RT_CPU0_P2_ROM_R_SCL ; 2 = SMB_RT_CPU0_P2_ROM_SCL
R683  Q_RES  33.2 1% CHIP  pkg 0201LF  page 300 : 1 = SMB_RT_CPU0_P2_ROM_R_SDA ; 2 = SMB_RT_CPU0_P2_ROM_SDA
R684  Q_RES  49.9 1% CHIP  pkg 0201LF  page 309 : 1 = SMB_RT_CPU0_P3_ROM_MUX_1D_SCL ; 2 = SMB_RT_CPU0_P3_ROM_MUX_1D_R_SCL
R685  Q_RES  33 5% CHIP  pkg 0402LF  page 81 : 1 = RST_PERST_E1S_0_R_N ; 2 = RST_PERST_E1S_0_N
R686  Q_RES  49.9 1% CHIP  pkg 0201LF  page 309 : 1 = SMB_RT_CPU0_P3_ROM_MUX_1D_SDA ; 2 = SMB_RT_CPU0_P3_ROM_MUX_1D_R_SDA
R687  Q_RES  33.2 1% CHIP  pkg 0201LF  page 311 : 1 = SMB_RT_CPU0_P3_ROM_R_SCL ; 2 = SMB_RT_CPU0_P3_ROM_SCL
R688  Q_RES  33.2 1% CHIP  pkg 0201LF  page 311 : 1 = SMB_RT_CPU0_P3_ROM_R_SDA ; 2 = SMB_RT_CPU0_P3_ROM_SDA
R689  Q_RES  33.2 1% CHIP  pkg 0201LF  page 333 : 1 = SMB_RT_CPU1_P1_ROM_R_SCL ; 2 = SMB_RT_CPU1_P1_ROM_SCL
R690  Q_RES  33.2 1% CHIP  pkg 0201LF  page 333 : 1 = SMB_RT_CPU1_P1_ROM_R_SDA ; 2 = SMB_RT_CPU1_P1_ROM_SDA
R691  Q_RES  49.9 1% CHIP  pkg 0201LF  page 342 : 1 = SMB_RT_CPU1_P2_ROM_MUX_1D_SCL ; 2 = SMB_RT_CPU1_P2_ROM_MUX_1D_R_SCL
R692  Q_RES  49.9 1% CHIP  pkg 0201LF  page 342 : 1 = SMB_RT_CPU1_P2_ROM_MUX_1D_SDA ; 2 = SMB_RT_CPU1_P2_ROM_MUX_1D_R_SDA
R693  Q_RES  33.2 1% CHIP  pkg 0201LF  page 344 : 1 = SMB_RT_CPU1_P2_ROM_R_SCL ; 2 = SMB_RT_CPU1_P2_ROM_SCL
R694  Q_RES  33.2 1% CHIP  pkg 0201LF  page 344 : 1 = SMB_RT_CPU1_P2_ROM_R_SDA ; 2 = SMB_RT_CPU1_P2_ROM_SDA
R695  Q_RES  22 1% CHIP  pkg 0201LF  page 353 : 1 = SMB_RT_CPU1_P3_ROM_MUX_1D_SCL ; 2 = SMB_RT_CPU1_P3_ROM_MUX_1D_R_SCL
R696  Q_RES  49.9 1% CHIP  pkg 0201LF  page 353 : 1 = SMB_RT_CPU1_P3_ROM_MUX_1D_SDA ; 2 = SMB_RT_CPU1_P3_ROM_MUX_1D_R_SDA
R697  Q_RES  0 5% CHIP  pkg 0201LF  page 355 : 1 = SMB_RT_CPU1_P3_ROM_R_SCL ; 2 = SMB_RT_CPU1_P3_ROM_SCL
R698  Q_RES  33.2 1% CHIP  pkg 0201LF  page 355 : 1 = SMB_RT_CPU1_P3_ROM_R_SDA ; 2 = SMB_RT_CPU1_P3_ROM_SDA
R699  Q_RES  1K 1% EMPTY  pkg 0201LF  page 321 : 1 = P1V8_CPU1_RT_1D ; 2 = RT_CPU1_P0_VQPS
R700  Q_RES  30K 1% EMPTY  pkg 0402LF  page 169 : 1 = P12V_AUX ; 2 = P12V_AUX_DSC_VOL
R701  Q_RES  200 1% CHIP  pkg 0201LF  page 321 : 1 = RT_CPU1_P0_VQPS ; 2 = GND
R702  Q_RES  10K 5% EMPTY  pkg 0402LF  page 78 : 1 = PWRGD_CPU0_PWROK ; 2 = GND
R703  Q_RES  10K 5% EMPTY  pkg 0402LF  page 78 : 1 = PWRGD_CPU1_PWROK ; 2 = GND
R704  Q_RES  0 5% EMPTY  pkg 0402LF  page 334 : 1 = P1V8_CPU1_RT_1D ; 2 = P1V8_CPU1_RT1_1A_1D
R705  Q_RES  0 5% EMPTY  pkg 0603LF  page 334 : 1 = P0V9_CPU1_RT_2D ; 2 = P0V9_CPU1_RT1_2A_2D
R706  Q_RES  4.7K 5% EMPTY  pkg 0201LF  page 320 : 1 = P1V8_CPU1_RT_1D ; 2 = GPIO2_RT_CPU1_P0
R707  Q_RES  10K 1% CHIP  pkg 0201LF  page 320 : 1 = GPIO2_RT_CPU1_P0 ; 2 = GND
R708  Q_RES  33 5% CHIP  pkg 0402LF  page 81 : 1 = FM_HDT_HDR_PWROK ; 2 = HDT_HDR_PWROK
R709  Q_RES  0 5% CHIP  pkg 0201LF  page 321 : 1 = NCF_CPU1_P0_GND ; 2 = GND
R710  Q_RES  1K 1% CHIP  pkg 0402LF  page 238 : 1 = PD_MB_FRU_WP ; 2 = GND
R711  Q_RES  0 5% CHIP  pkg 0201LF  page 321 : 1 = NCF_A1_CPU1_P0_GND ; 2 = GND
R712  Q_RES  0 5% CHIP  pkg 0603LF  page 334 : 1 = P0V9_CPU1_RT1_2A_2D ; 2 = P0V9_CPU1_RT1_2A
R713  Q_RES  10K 1% EMPTY  pkg 0402LF  page 238 : 1 = P3V3_AUX ; 2 = MB_FRU_ADDR2
R714  Q_RES  1K 1% CHIP  pkg 0402LF  page 238 : 1 = MB_FRU_ADDR2 ; 2 = GND
R715  Q_RES  10K 1% CHIP  pkg 0201LF  page 320 : 1 = GPIO3_RT_CPU1_P0 ; 2 = GND
R716  Q_RES  4.7K 5% EMPTY  pkg 0201LF  page 320 : 1 = P1V8_CPU1_RT_1D ; 2 = TEST0_RT_CPU1_P0
R717  Q_RES  10K 1% EMPTY  pkg 0402LF  page 238 : 1 = P3V3_AUX ; 2 = MB_FRU_ADDR1
R718  Q_RES  1K 1% CHIP  pkg 0402LF  page 238 : 1 = MB_FRU_ADDR1 ; 2 = GND
R719  Q_RES  4.7K 5% CHIP  pkg 0201LF  page 320 : 1 = TEST0_RT_CPU1_P0 ; 2 = GND
R720  Q_RES  4.7K 5% EMPTY  pkg 0201LF  page 320 : 1 = P1V8_CPU1_RT_1D ; 2 = TEST1_RT_CPU1_P0
R721  Q_RES  10K 1% CHIP  pkg 0402LF  page 238 : 1 = P3V3_AUX ; 2 = MB_FRU_ADDR0
R722  Q_RES  1K 1% EMPTY  pkg 0402LF  page 238 : 1 = MB_FRU_ADDR0 ; 2 = GND
R723  Q_RES  4.7K 5% CHIP  pkg 0201LF  page 320 : 1 = TEST1_RT_CPU1_P0 ; 2 = GND
R724  Q_RES  4.7K 5% EMPTY  pkg 0201LF  page 320 : 1 = P1V8_CPU1_RT_1D ; 2 = TEST2_RT_CPU1_P0
R725  Q_RES  4.7K 5% CHIP  pkg 0201LF  page 320 : 1 = TEST2_RT_CPU1_P0 ; 2 = GND
R726  Q_RES  4.7K 5% CHIP  pkg 0201LF  page 320 : 1 = JTAG_TEST_MODE_RT_CPU1_P0 ; 2 = GND
R727  Q_RES  4.7K 5% CHIP  pkg 0201LF  page 320 : 1 = P1V8_CPU1_RT_1D ; 2 = MODE_RT_CPU1_P0
R728  Q_RES  4.7K 5% EMPTY  pkg 0201LF  page 320 : 1 = MODE_RT_CPU1_P0 ; 2 = GND
R729  Q_RES  10K 5% EMPTY  pkg 0402LF  page 76 : 1 = PVDD18_S5_P0 ; 2 = UART_CPU0_SCM_UART1_TX
R730  Q_RES  10K 5% CHIP  pkg 0402LF  page 76 : 1 = PVDD18_S5_P1 ; 2 = SPI_CPU1_CLK
R731  Q_RES  0 5% CHIP  pkg 0201LF  page 331 : 1 = RST_RT_CPU1_P1_PERST_N ; 2 = RST_RT_CPU1_P1_PERST_R_N
R732  Q_RES  0 5% CHIP  pkg 0201LF  page 331 : 1 = RST_RT_CPU1_P1_RESET_N ; 2 = RST_RT_CPU1_P1_RESET_R_N
R733  Q_RES  100 1% EMPTY  pkg 0402LF  page 167 : 1 = P1V8_AUX ; 2 = FM_JTAG_BMC_R_OE
R734  Q_RES  0 5% CHIP  pkg 0402LF  page 167 : 1 = PRSNT_CPU0_N ; 2 = FM_PRSNT_CPU0_N
R735  Q_RES  1K 1% CHIP  pkg 0201LF  page 331 : 1 = P1V8_CPU1_RT_1D ; 2 = RT_CPU1_P1_ADDR3
R736  Q_RES  10K 5% EMPTY  pkg 0402LF  page 76 : 1 = PVDD18_S5_P1 ; 2 = PD_ESPI_CPU1_CLK2
R737  Q_RES  10K 5% CHIP  pkg 0402LF  page 76 : 1 = PVDD18_S5_P0 ; 2 = CPU0_ROM_TYPE_SELECT
R738  Q_RES  33 5% CHIP  pkg 0402LF  page 56 : 1 = SPI_CPU1_CLK ; 2 = SPI_CPU1_R_CLK
R739  Q_RES  10K 5% EMPTY  pkg 0402LF  page 76 : 1 = PVDD18_S5_P0 ; 2 = CLK_ESPI_CPU0_CLK1
R740  Q_RES  10K 5% EMPTY  pkg 0402LF  page 76 : 1 = PVDD18_S5_P0 ; 2 = CLK_CPU0_RTCCLK
R741  Q_RES  1K 1% EMPTY  pkg 0201LF  page 331 : 1 = RT_CPU1_P1_ADDR3 ; 2 = GND
R742  Q_RES  10K 5% EMPTY  pkg 0402LF  page 76 : 1 = PVDD18_S5_P0 ; 2 = PD_ESPI_CPU0_CLK2
R743  Q_RES  10K 5% CHIP  pkg 0402LF  page 76 : 1 = PVDD18_S5_P0 ; 2 = SPI_CPU0_CLK
R744  Q_RES  0 5% CHIP  pkg 0402LF  page 167 : 1 = PRSNT_CPU1_N ; 2 = FM_PRSNT_CPU1_N
R745  Q_RES  1K 1% EMPTY  pkg 0201LF  page 331 : 1 = P1V8_CPU1_RT_1D ; 2 = RT_CPU1_P1_ADDR2
R746  Q_RES  20K 1% CHIP  pkg 0201LF  page 331 : 1 = RT_CPU1_P1_ADDR2 ; 2 = GND
R747  Q_RES  1K 1% CHIP  pkg 0402LF  page 76 : 1 = GND ; 2 = UART_CPU0_SCM_UART1_TX
R748  Q_RES  10K 5% EMPTY  pkg 0402LF  page 76 : 1 = GND ; 2 = CPU0_ROM_TYPE_SELECT
R749  Q_RES  10K 1% CHIP  pkg 0201LF  page 331 : 1 = RST_RT_CPU1_P1_PERST_R_N ; 2 = GND
R750  Q_RES  30K 1% CHIP  pkg 0402LF  page 76 : 1 = GND ; 2 = CLK_ESPI_CPU0_CLK1
R751  Q_RES  10K 5% CHIP  pkg 0402LF  page 76 : 1 = GND ; 2 = CLK_CPU0_RTCCLK
R752  Q_RES  10K 1% CHIP  pkg 0201LF  page 331 : 1 = RST_RT_CPU1_P1_RESET_R_N ; 2 = GND
R753  Q_RES  10K 5% CHIP  pkg 0402LF  page 76 : 1 = GND ; 2 = PD_ESPI_CPU0_CLK2
R754  Q_RES  10K 5% EMPTY  pkg 0402LF  page 76 : 1 = GND ; 2 = SPI_CPU1_CLK
R755  Q_RES  4.7K 5% EMPTY  pkg 0201LF  page 331 : 1 = P1V8_CPU1_RT_1D ; 2 = RT_CPU1_P1_SCAN_MODE
R756  Q_RES  200 1% CHIP  pkg 0201LF  page 331 : 1 = RT_CPU1_P1_SCAN_MODE ; 2 = GND
R757  Q_RES  4.7K 5% EMPTY  pkg 0402LF  page 83 : 1 = E1S_0_P3V3_EN ; 2 = P3V3_AUX
R758  Q_RES  4.7K 5% EMPTY  pkg 0201LF  page 331 : 1 = P1V8_CPU1_RT_1D ; 2 = RST_RT_CPU1_P1_RESET_R_N
R759  Q_RES  4.7K 5% EMPTY  pkg 0201LF  page 331 : 1 = P1V8_CPU1_RT_1D ; 2 = JTAG_TEST_MODE_RT_CPU1_P1
R760  Q_RES  10K 5% CHIP  pkg 0402LF  page 76 : 1 = GND ; 2 = PD_ESPI_CPU1_CLK2
R761  Q_RES  15.4K 1% CHIP  pkg 0402LF  page 87 : 1 = PD_CHB_CPU0_DIMM_SAA ; 2 = GND
R762  Q_RES  23.2K 1% CHIP  pkg 0402LF  page 88 : 1 = PD_CHC_CPU0_DIMM_SAA ; 2 = GND
R763  Q_RES  35.7K 1% CHIP  pkg 0402LF  page 89 : 1 = PD_CHD_CPU0_DIMM_SAA ; 2 = GND
